(kicad_pcb
	(version 20241229)
	(generator "pcbnew")
	(generator_version "9.0")
	(general
		(thickness 1.6296)
		(legacy_teardrops no)
	)
	(paper "A3")
	(title_block
		(title "Thunderbolt to 10GbE adapter")
		(date "2026-04-21")
		(rev "1.1.0")
		(company "Antmicro Ltd")
		(comment 1 "www.antmicro.com")
		(comment 9 "footprints 313-317 of 703")
	)
	(layers
		(0 "F.Cu" signal)
		(4 "In1.Cu" signal)
		(6 "In2.Cu" signal)
		(8 "In3.Cu" signal)
		(10 "In4.Cu" signal)
		(12 "In5.Cu" signal)
		(14 "In6.Cu" signal)
		(2 "B.Cu" signal)
		(9 "F.Adhes" user "F.Adhesive")
		(11 "B.Adhes" user "B.Adhesive")
		(13 "F.Paste" user)
		(15 "B.Paste" user)
		(5 "F.SilkS" user "F.Silkscreen")
		(7 "B.SilkS" user "B.Silkscreen")
		(1 "F.Mask" user)
		(3 "B.Mask" user)
		(17 "Dwgs.User" user "User.Drawings")
		(19 "Cmts.User" user "User.Comments")
		(21 "Eco1.User" user "User.Eco1")
		(23 "Eco2.User" user "User.Eco2")
		(25 "Edge.Cuts" user)
		(27 "Margin" user)
		(31 "F.CrtYd" user "F.Courtyard")
		(29 "B.CrtYd" user "B.Courtyard")
		(35 "F.Fab" user)
		(33 "B.Fab" user)
	)
	(footprint "antmicro-footprints:R_0402_1005Metric"
		(layer "F.Cu")
		(at 143.849999 113.150002)
		(descr "Resistor SMD 0402")
		(tags "resistor SMD 0402")
		(property "Reference" "R95"
			(at 15.349999 17.25 0)
			(layer "F.SilkS")
			(effects
				(font
					(size 0.7 0.7)
					(thickness 0.15)
				)
			)
		)
		(property "Value" "R_0R_0402"
			(at -1.011843 1.772047 0)
			(layer "F.Fab")
			(effects
				(font
					(size 0.7 0.7)
					(thickness 0.15)
				)
				(justify left bottom)
			)
		)
		(property "Datasheet" "https://industrial.panasonic.com/cdbs/www-data/pdf/RDA0000/AOA0000C301.pdf"
			(at 0 0 0)
			(layer "F.Fab")
			(hide yes)
			(effects
				(font
					(size 1.27 1.27)
					(thickness 0.15)
				)
			)
		)
		(property "Description" "SMD Chip Resistor, Jumper, 0 ohm, 100 mW, 0402 [1005 Metric], Thick Film, General Purpose"
			(at 0 0 0)
			(layer "F.Fab")
			(hide yes)
			(effects
				(font
					(size 1.27 1.27)
					(thickness 0.15)
				)
			)
		)
		(property "MPN" "ERJ2GE0R00X"
			(at 0 0 0)
			(unlocked yes)
			(layer "F.Fab")
			(hide yes)
			(effects
				(font
					(size 1 1)
					(thickness 0.15)
				)
			)
		)
		(property "Manufacturer" "Panasonic"
			(at 0 0 0)
			(unlocked yes)
			(layer "F.Fab")
			(hide yes)
			(effects
				(font
					(size 1 1)
					(thickness 0.15)
				)
			)
		)
		(property "License" "Apache-2.0"
			(at 0 0 0)
			(unlocked yes)
			(layer "F.Fab")
			(hide yes)
			(effects
				(font
					(size 1 1)
					(thickness 0.15)
				)
			)
		)
		(property "Author" "Antmicro"
			(at 0 0 0)
			(unlocked yes)
			(layer "F.Fab")
			(hide yes)
			(effects
				(font
					(size 1 1)
					(thickness 0.15)
				)
			)
		)
		(property "Val" "0R"
			(at 0 0 0)
			(unlocked yes)
			(layer "F.Fab")
			(hide yes)
			(effects
				(font
					(size 1 1)
					(thickness 0.15)
				)
			)
		)
		(property "Tolerance" "~"
			(at 0 0 0)
			(unlocked yes)
			(layer "F.Fab")
			(hide yes)
			(effects
				(font
					(size 1 1)
					(thickness 0.15)
				)
			)
		)
		(property "Current" "1A"
			(at 0 0 0)
			(unlocked yes)
			(layer "F.Fab")
			(hide yes)
			(effects
				(font
					(size 1 1)
					(thickness 0.15)
				)
			)
		)
		(sheetname "/X710 DCDC converters/")
		(sheetfile "DCDC_converters_X710.kicad_sch")
		(attr smd)
		(fp_rect
			(start -0.925 -0.47)
			(end 0.925 0.47)
			(stroke
				(width 0.05)
				(type default)
			)
			(fill no)
			(layer "F.CrtYd")
		)
		(fp_rect
			(start -0.5 -0.25)
			(end 0.5 0.25)
			(stroke
				(width 0.15)
				(type solid)
			)
			(fill no)
			(layer "F.Fab")
		)
		(fp_text user "${REFERENCE}"
			(at -0.95 3.168 0)
			(layer "F.Fab")
			(effects
				(font
					(size 0.7 0.7)
					(thickness 0.15)
				)
				(justify left bottom)
			)
		)
		(fp_text user "License: Apache-2.0"
			(at -0.95 5.169 0)
			(layer "F.Fab")
			(effects
				(font
					(size 0.7 0.7)
					(thickness 0.15)
				)
				(justify left bottom)
			)
		)
		(fp_text user "Author: Antmicro"
			(at -0.95 4.169 0)
			(layer "F.Fab")
			(effects
				(font
					(size 0.7 0.7)
					(thickness 0.15)
				)
				(justify left bottom)
			)
		)
		(pad "1" smd roundrect
			(at -0.48 0)
			(size 0.59 0.64)
			(layers "F.Cu" "F.Mask" "F.Paste")
			(roundrect_rratio 0.25)
			(net 381 "/X710 DCDC converters/1V0_PG")
			(pintype "passive")
		)
		(pad "2" smd roundrect
			(at 0.48 0)
			(size 0.59 0.64)
			(layers "F.Cu" "F.Mask" "F.Paste")
			(roundrect_rratio 0.25)
			(net 386 "/X710 DCDC converters/DVDD_EN")
			(pintype "passive")
		)
	)
	(footprint "antmicro-footprints:BarrelJack_Pin1.3mm_694103107102"
		(layer "F.Cu")
		(at 133 50 90)
		(property "Reference" "J9"
			(at 3 5.4 90)
			(layer "F.SilkS")
			(effects
				(font
					(size 0.7 0.7)
					(thickness 0.15)
				)
				(justify left bottom)
			)
		)
		(property "Value" "BarrelJack_Pin1.3mm_694103107102"
			(at -4.92 6.81 90)
			(layer "F.Fab")
			(effects
				(font
					(size 0.7 0.7)
					(thickness 0.15)
				)
				(justify left bottom)
			)
		)
		(property "Datasheet" "https://www.we-online.de/katalog/datasheet/694103107102.pdf"
			(at 0 0 90)
			(layer "F.Fab")
			(hide yes)
			(effects
				(font
					(size 0.7 0.7)
					(thickness 0.15)
				)
				(justify left bottom)
			)
		)
		(property "Description" "DC Power Connector, Jack, 5 A, 1.35 mm, PCB Mount, Surface Mount"
			(at 0 0 90)
			(layer "F.Fab")
			(hide yes)
			(effects
				(font
					(size 0.7 0.7)
					(thickness 0.15)
				)
				(justify left bottom)
			)
		)
		(property "MPN" "694103107102"
			(at 0 0 90)
			(unlocked yes)
			(layer "F.Fab")
			(hide yes)
			(effects
				(font
					(size 1 1)
					(thickness 0.15)
				)
			)
		)
		(property "Manufacturer" "Würth Elektronik"
			(at 0 0 90)
			(unlocked yes)
			(layer "F.Fab")
			(hide yes)
			(effects
				(font
					(size 1 1)
					(thickness 0.15)
				)
			)
		)
		(property "Author" "Antmicro"
			(at 0 0 90)
			(unlocked yes)
			(layer "F.Fab")
			(hide yes)
			(effects
				(font
					(size 1 1)
					(thickness 0.15)
				)
			)
		)
		(property "License" "Apache-2.0"
			(at 0 0 90)
			(unlocked yes)
			(layer "F.Fab")
			(hide yes)
			(effects
				(font
					(size 1 1)
					(thickness 0.15)
				)
			)
		)
		(sheetname "/Power input/")
		(sheetfile "power_input.kicad_sch")
		(attr smd dnp)
		(fp_line
			(start 4.85 -4)
			(end 4.85 4)
			(stroke
				(width 0.15)
				(type solid)
			)
			(layer "F.SilkS")
		)
		(fp_line
			(start 2.65 -4)
			(end 4.85 -4)
			(stroke
				(width 0.15)
				(type solid)
			)
			(layer "F.SilkS")
		)
		(fp_line
			(start 0.05 -4)
			(end -1.85 -4)
			(stroke
				(width 0.15)
				(type solid)
			)
			(layer "F.SilkS")
		)
		(fp_line
			(start 2.65 4)
			(end 4.85 4)
			(stroke
				(width 0.15)
				(type solid)
			)
			(layer "F.SilkS")
		)
		(fp_line
			(start 0.05 4)
			(end -1.85 4)
			(stroke
				(width 0.15)
				(type solid)
			)
			(layer "F.SilkS")
		)
		(fp_line
			(start -4.45 4)
			(end -4.45 -4)
			(stroke
				(width 0.15)
				(type solid)
			)
			(layer "F.SilkS")
		)
		(fp_rect
			(start -4.85 5.8)
			(end 5.25 -5.8)
			(stroke
				(width 0.05)
				(type solid)
			)
			(fill no)
			(layer "F.CrtYd")
		)
		(fp_rect
			(start -4.45 4.9)
			(end 4.85 -4.9)
			(stroke
				(width 0.15)
				(type solid)
			)
			(fill no)
			(layer "F.Fab")
		)
		(fp_text user "plug:"
			(at 5.334 -0.254 90)
			(unlocked yes)
			(layer "F.Fab")
			(effects
				(font
					(size 0.7 0.7)
					(thickness 0.15)
				)
				(justify left bottom)
			)
		)
		(fp_text user "Author: Antmicro"
			(at -4.85 10.2 90)
			(layer "F.Fab")
			(effects
				(font
					(size 0.7 0.7)
					(thickness 0.15)
				)
				(justify left bottom)
			)
		)
		(fp_text user "Ø3.5/1.35mm"
			(at 5.334 1.016 90)
			(unlocked yes)
			(layer "F.Fab")
			(effects
				(font
					(size 0.7 0.7)
					(thickness 0.15)
				)
				(justify left bottom)
			)
		)
		(fp_text user "License: Apache-2.0"
			(at -4.85 7.8 90)
			(layer "F.Fab")
			(effects
				(font
					(size 0.7 0.7)
					(thickness 0.15)
				)
				(justify left bottom)
			)
		)
		(fp_text user "${REFERENCE}"
			(at -4.85 9 90)
			(layer "F.Fab")
			(effects
				(font
					(size 0.7 0.7)
					(thickness 0.15)
				)
				(justify left bottom)
			)
		)
		(pad "" np_thru_hole circle
			(at -1.65 0 180)
			(size 1 1)
			(drill 1)
			(layers "*.Cu" "*.Mask" "F.SilkS")
		)
		(pad "" np_thru_hole circle
			(at 3.35 0 180)
			(size 1 1)
			(drill 1)
			(layers "*.Cu" "*.Mask" "F.SilkS")
		)
		(pad "1" smd rect
			(at -3.15 4.3)
			(size 2.2 2.2)
			(layers "F.Cu" "F.Mask" "F.Paste")
			(net 412 "Net-(D15-C)")
			(pinfunction "1")
			(pintype "passive")
		)
		(pad "1" smd rect
			(at 1.35 4.3)
			(size 2.2 2.2)
			(layers "F.Cu" "F.Mask" "F.Paste")
			(net 412 "Net-(D15-C)")
			(pinfunction "1")
			(pintype "passive")
		)
		(pad "2" smd rect
			(at 1.35 -4.3)
			(size 2.2 2.2)
			(layers "F.Cu" "F.Mask" "F.Paste")
			(net 23 "GND")
			(pinfunction "2")
			(pintype "passive")
		)
		(pad "3" smd rect
			(at -3.15 -4.3)
			(size 2.2 2.2)
			(layers "F.Cu" "F.Mask" "F.Paste")
			(net 23 "GND")
			(pinfunction "3")
			(pintype "passive")
		)
	)
	(footprint "antmicro-footprints:R_0402_1005Metric"
		(layer "F.Cu")
		(at 117 145.6)
		(descr "Resistor SMD 0402")
		(tags "resistor SMD 0402")
		(property "Reference" "R1"
			(at 1 0.4 0)
			(layer "F.SilkS")
			(effects
				(font
					(size 0.7 0.7)
					(thickness 0.15)
				)
				(justify left bottom)
			)
		)
		(property "Value" "R_2k2_0402"
			(at -1.011843 1.772047 0)
			(layer "F.Fab")
			(effects
				(font
					(size 0.7 0.7)
					(thickness 0.15)
				)
				(justify left bottom)
			)
		)
		(property "Datasheet" "https://www.bourns.com/docs/product-datasheets/cr.pdf"
			(at 0 0 0)
			(layer "F.Fab")
			(hide yes)
			(effects
				(font
					(size 1.27 1.27)
					(thickness 0.15)
				)
			)
		)
		(property "Description" "SMD Chip Resistor, 2.2 kohm, ± 1%, 62.5 mW, 0402 [1005 Metric], Thick Film, General Purpose"
			(at 0 0 0)
			(layer "F.Fab")
			(hide yes)
			(effects
				(font
					(size 1.27 1.27)
					(thickness 0.15)
				)
			)
		)
		(property "MPN" "CR0402-FX-2201GLF"
			(at 0 0 0)
			(unlocked yes)
			(layer "F.Fab")
			(hide yes)
			(effects
				(font
					(size 1 1)
					(thickness 0.15)
				)
			)
		)
		(property "Manufacturer" "Bourns"
			(at 0 0 0)
			(unlocked yes)
			(layer "F.Fab")
			(hide yes)
			(effects
				(font
					(size 1 1)
					(thickness 0.15)
				)
			)
		)
		(property "License" "Apache-2.0"
			(at 0 0 0)
			(unlocked yes)
			(layer "F.Fab")
			(hide yes)
			(effects
				(font
					(size 1 1)
					(thickness 0.15)
				)
			)
		)
		(property "Author" "Antmicro"
			(at 0 0 0)
			(unlocked yes)
			(layer "F.Fab")
			(hide yes)
			(effects
				(font
					(size 1 1)
					(thickness 0.15)
				)
			)
		)
		(property "Val" "2k2"
			(at 0 0 0)
			(unlocked yes)
			(layer "F.Fab")
			(hide yes)
			(effects
				(font
					(size 1 1)
					(thickness 0.15)
				)
			)
		)
		(property "Tolerance" "1%"
			(at 0 0 0)
			(unlocked yes)
			(layer "F.Fab")
			(hide yes)
			(effects
				(font
					(size 1 1)
					(thickness 0.15)
				)
			)
		)
		(sheetname "/USB-C connector/")
		(sheetfile "USB-C_connector.kicad_sch")
		(attr smd)
		(fp_rect
			(start -0.925 -0.47)
			(end 0.925 0.47)
			(stroke
				(width 0.05)
				(type default)
			)
			(fill no)
			(layer "F.CrtYd")
		)
		(fp_rect
			(start -0.5 -0.25)
			(end 0.5 0.25)
			(stroke
				(width 0.15)
				(type solid)
			)
			(fill no)
			(layer "F.Fab")
		)
		(fp_text user "${REFERENCE}"
			(at -0.95 3.168 0)
			(layer "F.Fab")
			(effects
				(font
					(size 0.7 0.7)
					(thickness 0.15)
				)
				(justify left bottom)
			)
		)
		(fp_text user "License: Apache-2.0"
			(at -0.95 5.169 0)
			(layer "F.Fab")
			(effects
				(font
					(size 0.7 0.7)
					(thickness 0.15)
				)
				(justify left bottom)
			)
		)
		(fp_text user "Author: Antmicro"
			(at -0.95 4.169 0)
			(layer "F.Fab")
			(effects
				(font
					(size 0.7 0.7)
					(thickness 0.15)
				)
				(justify left bottom)
			)
		)
		(pad "1" smd roundrect
			(at -0.48 0)
			(size 0.59 0.64)
			(layers "F.Cu" "F.Mask" "F.Paste")
			(roundrect_rratio 0.25)
			(net 23 "GND")
			(pintype "passive")
		)
		(pad "2" smd roundrect
			(at 0.48 0)
			(size 0.59 0.64)
			(layers "F.Cu" "F.Mask" "F.Paste")
			(roundrect_rratio 0.25)
			(net 434 "Net-(U1-ISET)")
			(pintype "passive")
		)
	)
	(footprint "antmicro-footprints:Mech_Lightpipe_Mentor_1271.1001"
		(layer "F.Cu")
		(at 139.55 147.813534 180)
		(descr "1x1  Horizontal Light Guide with transparent pipe")
		(tags "Horizontal, THT, MECHANICAL, MODULE")
		(property "Reference" "H2"
			(at 1.8 -3.386466 0)
			(unlocked yes)
			(layer "F.SilkS")
			(effects
				(font
					(size 0.7 0.7)
					(thickness 0.15)
				)
				(justify left bottom)
			)
		)
		(property "Value" "Lightpipe_Mentor_1271.1001"
			(at 0 9 180)
			(unlocked yes)
			(layer "F.Fab")
			(effects
				(font
					(size 0.7 0.7)
					(thickness 0.15)
				)
				(justify left bottom)
			)
		)
		(property "Datasheet" "https://www.mentor.de.com/productpdfs/ll/ll14-20.pdf"
			(at 0 0 180)
			(layer "F.Fab")
			(hide yes)
			(effects
				(font
					(size 1.27 1.27)
					(thickness 0.15)
				)
			)
		)
		(property "Description" "Light Pipe, 14.45 mm, 1 Pipe, Circular, PC Board, Transparent"
			(at 0 0 180)
			(layer "F.Fab")
			(hide yes)
			(effects
				(font
					(size 1.27 1.27)
					(thickness 0.15)
				)
			)
		)
		(property "MPN" "1271.1001"
			(at 0 0 180)
			(unlocked yes)
			(layer "F.Fab")
			(hide yes)
			(effects
				(font
					(size 1 1)
					(thickness 0.15)
				)
			)
		)
		(property "Manufacturer" "Mentor Worldwide"
			(at 0 0 180)
			(unlocked yes)
			(layer "F.Fab")
			(hide yes)
			(effects
				(font
					(size 1 1)
					(thickness 0.15)
				)
			)
		)
		(property "Author" "Antmicro"
			(at 0 0 180)
			(unlocked yes)
			(layer "F.Fab")
			(hide yes)
			(effects
				(font
					(size 1 1)
					(thickness 0.15)
				)
			)
		)
		(property "License" "Apache-2.0"
			(at 0 0 180)
			(unlocked yes)
			(layer "F.Fab")
			(hide yes)
			(effects
				(font
					(size 1 1)
					(thickness 0.15)
				)
			)
		)
		(sheetname "/")
		(sheetfile "thunderbolt-to-10gbe-adapter.kicad_sch")
		(attr through_hole)
		(fp_rect
			(start -1.55 -2.1)
			(end 1.55 1.3)
			(stroke
				(width 0.05)
				(type solid)
			)
			(fill no)
			(layer "F.SilkS")
		)
		(fp_rect
			(start -1.75 -2.3)
			(end 1.75 1.475)
			(stroke
				(width 0.05)
				(type solid)
			)
			(fill no)
			(layer "F.CrtYd")
		)
		(fp_rect
			(start -1.4732 -8.128)
			(end 1.4732 6.2484)
			(stroke
				(width 0.15)
				(type solid)
			)
			(fill no)
			(layer "F.Fab")
		)
		(fp_text user "License: Apache-2.0"
			(at -1.8 11.7 180)
			(layer "F.Fab")
			(effects
				(font
					(size 0.7 0.7)
					(thickness 0.15)
				)
				(justify left bottom)
			)
		)
		(fp_text user "Author: Antmicro"
			(at -1.8 10.5 180)
			(layer "F.Fab")
			(effects
				(font
					(size 0.7 0.7)
					(thickness 0.15)
				)
				(justify left bottom)
			)
		)
		(fp_text user "${REFERENCE}"
			(at -1.8 12.9 180)
			(layer "F.Fab")
			(effects
				(font
					(size 0.7 0.7)
					(thickness 0.15)
				)
				(justify left bottom)
			)
		)
		(pad "" np_thru_hole circle
			(at 0 0 180)
			(size 2.3 2.3)
			(drill 2.3)
			(layers "*.Cu" "*.Mask")
		)
	)
	(footprint "antmicro-footprints:MP_Pad6mm_Drill3.2mm"
		(layer "F.Cu")
		(at 120 135.25)
		(property "Reference" "MP1"
			(at 1.5 -3.15 0)
			(layer "F.SilkS")
			(effects
				(font
					(size 0.7 0.7)
					(thickness 0.15)
				)
				(justify left bottom)
			)
		)
		(property "Value" "MP_Pad6mm_Drill3.2mm"
			(at 0 3.9 0)
			(layer "F.Fab")
			(effects
				(font
					(size 0.7 0.7)
					(thickness 0.15)
				)
				(justify left bottom)
			)
		)
		(property "Description" "Mechanical part"
			(at 0 0 0)
			(layer "F.Fab")
			(hide yes)
			(effects
				(font
					(size 1.27 1.27)
					(thickness 0.15)
				)
			)
		)
		(property "Author" "Antmicro"
			(at 0 0 0)
			(unlocked yes)
			(layer "F.Fab")
			(hide yes)
			(effects
				(font
					(size 1 1)
					(thickness 0.15)
				)
			)
		)
		(property "License" "Apache-2.0"
			(at 0 0 0)
			(unlocked yes)
			(layer "F.Fab")
			(hide yes)
			(effects
				(font
					(size 1 1)
					(thickness 0.15)
				)
			)
		)
		(sheetname "/")
		(sheetfile "thunderbolt-to-10gbe-adapter.kicad_sch")
		(attr exclude_from_pos_files exclude_from_bom)
		(fp_circle
			(center 0 0)
			(end 3.25 0)
			(stroke
				(width 0.05)
				(type default)
			)
			(fill no)
			(layer "F.CrtYd")
		)
		(fp_text user "License: Apache-2.0"
			(at -0.178 8.425 0)
			(layer "F.Fab")
			(effects
				(font
					(size 0.7 0.7)
					(thickness 0.15)
				)
				(justify left bottom)
			)
		)
		(fp_text user "Author: Antmicro"
			(at -0.178 7.225 0)
			(layer "F.Fab")
			(effects
				(font
					(size 0.7 0.7)
					(thickness 0.15)
				)
				(justify left bottom)
			)
		)
		(fp_text user "${REFERENCE}"
			(at -0.178 6.025 0)
			(layer "F.Fab")
			(effects
				(font
					(size 0.7 0.7)
					(thickness 0.15)
				)
				(justify left bottom)
			)
		)
		(pad "1" thru_hole circle
			(at 0 0)
			(size 6 6)
			(drill 3.2)
			(layers "*.Cu" "*.Mask")
			(remove_unused_layers no)
			(net 23 "GND")
			(pintype "passive")
		)
	)
)
